# T6G (Grand Teton) — schematic netlist excerpt (pin names and nets, part order shuffled) for the footprints in the layout excerpt that follows; sources: Cadence DE-HDL packaged netlist, KiCad conversion of 04192023_DAF0TMB3IC0_F0TG_MB_C_brd_V02_OCP.brd

C5022  Q_CAP  1000PF 50V 5% X7R  pkg 0402  page 217 : A = GND ; B = PWRGD_PVDDCR_CPU1_P1
C412  Q_CAP  4.7UF 6.3V 20% X6S  pkg 0402  page 345 : A = P0V9_CPU1_RT2_2A ; B = GND

(kicad_pcb
	(version 20260206)
	(generator "pcbnew")
	(generator_version "10.0")
	(general
		(thickness 1.6)
		(legacy_teardrops no)
	)
	(paper "A4")
	(title_block
		(title "04192023_DAF0TMB3IC0_F0TG_MB_C_brd_V02_OCP.brd")
		(comment 1 "Grand Teton / footprints 8337-8338 of 8354")
	)
	(layers
		(0 "F.Cu" signal "TOP")
		(4 "In1.Cu" signal "GND")
		(6 "In2.Cu" signal "IN1")
		(8 "In3.Cu" signal "GND1")
		(10 "In4.Cu" signal "IN2")
		(12 "In5.Cu" signal "GND2")
		(14 "In6.Cu" signal "IN3")
		(16 "In7.Cu" signal "GND3")
		(18 "In8.Cu" signal "VCC")
		(20 "In9.Cu" signal "VCC1")
		(22 "In10.Cu" signal "GND4")
		(24 "In11.Cu" signal "IN4")
		(26 "In12.Cu" signal "GND5")
		(28 "In13.Cu" signal "IN5")
		(30 "In14.Cu" signal "GND6")
		(32 "In15.Cu" signal "IN6")
		(34 "In16.Cu" signal "GND7")
		(2 "B.Cu" signal "BOTTOM")
		(9 "F.Adhes" user "F.Adhesive")
		(11 "B.Adhes" user "B.Adhesive")
		(13 "F.Paste" user "Package Geometry/Pastemask Top")
		(15 "B.Paste" user "Package Geometry/Pastemask Bottom")
		(5 "F.SilkS" user "Ref Des/Silkscreen Top")
		(7 "B.SilkS" user "Ref Des/Silkscreen Bottom")
		(1 "F.Mask" user "Board Geometry/Soldermask Top")
		(3 "B.Mask" user "Board Geometry/Soldermask Bottom")
		(17 "Dwgs.User" user "User.Drawings")
		(19 "Cmts.User" user "User.Comments")
		(21 "Eco1.User" user "User.Eco1")
		(23 "Eco2.User" user "User.Eco2")
		(25 "Edge.Cuts" user "Board Geometry/Outline")
		(27 "Margin" user)
		(31 "F.CrtYd" user "Package Geometry/Place Bound Top")
		(29 "B.CrtYd" user "Package Geometry/Place Bound Bottom")
		(35 "F.Fab" user "Ref Des/Assembly Top")
		(33 "B.Fab" user "Ref Des/Assembly Bottom")
	)
	(footprint ""
		(layer "B.Cu")
		(at 22.479 -365.76 180)
		(property "Reference" "C5022"
			(at 0 0 0)
			(layer "B.SilkS")
			(hide yes)
			(effects
				(font
					(size 1.27 1.27)
				)
				(justify mirror)
			)
		)
		(property "Value" ""
			(at 0 0 0)
			(layer "B.Fab")
			(effects
				(font
					(size 1.27 1.27)
				)
				(justify mirror)
			)
		)
		(duplicate_pad_numbers_are_jumpers no)
		(fp_line
			(start 0.7874 0.4064)
			(end 0.7874 -0.4064)
			(stroke
				(width 0.1524)
				(type default)
			)
			(layer "B.SilkS")
		)
		(fp_line
			(start 0.7874 -0.4064)
			(end -0.7874 -0.4064)
			(stroke
				(width 0.1524)
				(type default)
			)
			(layer "B.SilkS")
		)
		(fp_line
			(start -0.7874 0.4064)
			(end 0.7874 0.4064)
			(stroke
				(width 0.1524)
				(type default)
			)
			(layer "B.SilkS")
		)
		(fp_line
			(start -0.7874 -0.4064)
			(end -0.7874 0.4064)
			(stroke
				(width 0.1524)
				(type default)
			)
			(layer "B.SilkS")
		)
		(fp_line
			(start 0.67945 0.3048)
			(end 0.67945 -0.305054)
			(stroke
				(width 0.1)
				(type default)
			)
			(layer "B.Fab")
		)
		(fp_line
			(start 0.67945 -0.305054)
			(end 0.12065 -0.305054)
			(stroke
				(width 0.1)
				(type default)
			)
			(layer "B.Fab")
		)
		(fp_line
			(start 0.12065 0.3048)
			(end 0.67945 0.3048)
			(stroke
				(width 0.1)
				(type default)
			)
			(layer "B.Fab")
		)
		(fp_line
			(start 0.12065 0.2794)
			(end 0.12065 0.3048)
			(stroke
				(width 0.1)
				(type default)
			)
			(layer "B.Fab")
		)
		(fp_line
			(start 0.12065 -0.2794)
			(end -0.12065 -0.2794)
			(stroke
				(width 0.1)
				(type default)
			)
			(layer "B.Fab")
		)
		(fp_line
			(start 0.12065 -0.305054)
			(end 0.12065 -0.2794)
			(stroke
				(width 0.1)
				(type default)
			)
			(layer "B.Fab")
		)
		(fp_line
			(start -0.120396 0.3048)
			(end -0.120396 0.2794)
			(stroke
				(width 0.1)
				(type default)
			)
			(layer "B.Fab")
		)
		(fp_line
			(start -0.120396 0.2794)
			(end 0.12065 0.2794)
			(stroke
				(width 0.1)
				(type default)
			)
			(layer "B.Fab")
		)
		(fp_line
			(start -0.12065 -0.2794)
			(end -0.12065 -0.3048)
			(stroke
				(width 0.1)
				(type default)
			)
			(layer "B.Fab")
		)
		(fp_line
			(start -0.12065 -0.3048)
			(end -0.67945 -0.3048)
			(stroke
				(width 0.1)
				(type default)
			)
			(layer "B.Fab")
		)
		(fp_line
			(start -0.67945 0.3048)
			(end -0.120396 0.3048)
			(stroke
				(width 0.1)
				(type default)
			)
			(layer "B.Fab")
		)
		(fp_line
			(start -0.67945 -0.3048)
			(end -0.67945 0.3048)
			(stroke
				(width 0.1)
				(type default)
			)
			(layer "B.Fab")
		)
		(pad "1" smd circle
			(at 0.40005 0)
			(size 0 0)
			(layers "B.Cu" "B.Mask" "B.Paste")
			(net "GND")
		)
		(pad "2" smd circle
			(at -0.40005 0)
			(size 0 0)
			(layers "B.Cu" "B.Mask" "B.Paste")
			(net "PWRGD_PVDDCR_CPU1_P1")
		)
	)
	(footprint ""
		(layer "B.Cu")
		(at 163.819078 -390.560052 90)
		(property "Reference" "C412"
			(at 0 0 90)
			(layer "B.SilkS")
			(hide yes)
			(effects
				(font
					(size 1.27 1.27)
				)
				(justify mirror)
			)
		)
		(property "Value" ""
			(at 0 0 90)
			(layer "B.Fab")
			(effects
				(font
					(size 1.27 1.27)
				)
				(justify mirror)
			)
		)
		(duplicate_pad_numbers_are_jumpers no)
		(fp_line
			(start 0.7874 -0.4064)
			(end -0.7874 -0.4064)
			(stroke
				(width 0.1524)
				(type default)
			)
			(layer "B.SilkS")
		)
		(fp_line
			(start -0.7874 -0.4064)
			(end -0.7874 0.4064)
			(stroke
				(width 0.1524)
				(type default)
			)
			(layer "B.SilkS")
		)
		(fp_line
			(start 0.7874 0.4064)
			(end 0.7874 -0.4064)
			(stroke
				(width 0.1524)
				(type default)
			)
			(layer "B.SilkS")
		)
		(fp_line
			(start -0.7874 0.4064)
			(end 0.7874 0.4064)
			(stroke
				(width 0.1524)
				(type default)
			)
			(layer "B.SilkS")
		)
		(fp_line
			(start 0.67945 -0.305054)
			(end 0.12065 -0.305054)
			(stroke
				(width 0.1)
				(type default)
			)
			(layer "B.Fab")
		)
		(fp_line
			(start 0.12065 -0.305054)
			(end 0.12065 -0.2794)
			(stroke
				(width 0.1)
				(type default)
			)
			(layer "B.Fab")
		)
		(fp_line
			(start -0.12065 -0.3048)
			(end -0.67945 -0.3048)
			(stroke
				(width 0.1)
				(type default)
			)
			(layer "B.Fab")
		)
		(fp_line
			(start -0.67945 -0.3048)
			(end -0.67945 0.3048)
			(stroke
				(width 0.1)
				(type default)
			)
			(layer "B.Fab")
		)
		(fp_line
			(start 0.12065 -0.2794)
			(end -0.12065 -0.2794)
			(stroke
				(width 0.1)
				(type default)
			)
			(layer "B.Fab")
		)
		(fp_line
			(start -0.12065 -0.2794)
			(end -0.12065 -0.3048)
			(stroke
				(width 0.1)
				(type default)
			)
			(layer "B.Fab")
		)
		(fp_line
			(start 0.12065 0.2794)
			(end 0.12065 0.3048)
			(stroke
				(width 0.1)
				(type default)
			)
			(layer "B.Fab")
		)
		(fp_line
			(start -0.120396 0.2794)
			(end 0.12065 0.2794)
			(stroke
				(width 0.1)
				(type default)
			)
			(layer "B.Fab")
		)
		(fp_line
			(start 0.67945 0.3048)
			(end 0.67945 -0.305054)
			(stroke
				(width 0.1)
				(type default)
			)
			(layer "B.Fab")
		)
		(fp_line
			(start 0.12065 0.3048)
			(end 0.67945 0.3048)
			(stroke
				(width 0.1)
				(type default)
			)
			(layer "B.Fab")
		)
		(fp_line
			(start -0.120396 0.3048)
			(end -0.120396 0.2794)
			(stroke
				(width 0.1)
				(type default)
			)
			(layer "B.Fab")
		)
		(fp_line
			(start -0.67945 0.3048)
			(end -0.120396 0.3048)
			(stroke
				(width 0.1)
				(type default)
			)
			(layer "B.Fab")
		)
		(pad "1" smd circle
			(at 0.40005 0 270)
			(size 0 0)
			(layers "B.Cu" "B.Mask" "B.Paste")
			(net "P0V9_CPU1_RT2_2A")
		)
		(pad "2" smd circle
			(at -0.40005 0 270)
			(size 0 0)
			(layers "B.Cu" "B.Mask" "B.Paste")
			(net "GND")
		)
	)
)
